(kicad_pcb
	(version 20260206)
	(generator "pcbnew")
	(generator_version "10.0")
	(general
		(thickness 1.6)
		(legacy_teardrops no)
	)
	(paper "A4")
	(title_block
		(title "peb — Lightning_PEB_BRD.brd")
		(comment 1 "Lightning (Wiwynn / Facebook NVMe JBOF) / footprints 871-878 of 2563")
	)
	(layers
		(0 "F.Cu" signal "TOP")
		(4 "In1.Cu" signal "L2GND")
		(6 "In2.Cu" signal "L3")
		(8 "In3.Cu" signal "L4VCC")
		(10 "In4.Cu" signal "L5VCC")
		(12 "In5.Cu" signal "L6")
		(14 "In6.Cu" signal "L7GND")
		(2 "B.Cu" signal "BOTTOM")
		(9 "F.Adhes" user "F.Adhesive")
		(11 "B.Adhes" user "B.Adhesive")
		(13 "F.Paste" user "Package Geometry/Pastemask Top")
		(15 "B.Paste" user "Package Geometry/Pastemask Bottom")
		(5 "F.SilkS" user "Ref Des/Silkscreen Top")
		(7 "B.SilkS" user "Ref Des/Silkscreen Bottom")
		(1 "F.Mask" user "Board Geometry/Soldermask Top")
		(3 "B.Mask" user "Board Geometry/Soldermask Bottom")
		(17 "Dwgs.User" user "User.Drawings")
		(19 "Cmts.User" user "User.Comments")
		(21 "Eco1.User" user "User.Eco1")
		(23 "Eco2.User" user "User.Eco2")
		(25 "Edge.Cuts" user "Board Geometry/Outline")
		(27 "Margin" user)
		(31 "F.CrtYd" user "Package Geometry/Place Bound Top")
		(29 "B.CrtYd" user "Package Geometry/Place Bound Bottom")
		(35 "F.Fab" user "Ref Des/Assembly Top")
		(33 "B.Fab" user "Ref Des/Assembly Bottom")
	)
	(footprint ""
		(layer "F.Cu")
		(at 11.9126 -125.0188 180)
		(property "Reference" "R18"
			(at 0 0 180)
			(layer "F.SilkS")
			(hide yes)
			(effects
				(font
					(size 1.27 1.27)
				)
			)
		)
		(property "Value" "0R2J-2-GP"
			(at 0.064008 -3.993896 180)
			(unlocked yes)
			(layer "F.Fab")
			(hide yes)
			(effects
				(font
					(size 1.016 1.016)
					(thickness 0.1524)
				)
			)
		)
		(property "Device Type" "R402H16"
			(at 0.064008 -5.517896 180)
			(unlocked yes)
			(layer "F.Fab")
			(hide yes)
			(effects
				(font
					(size 1.016 1.016)
					(thickness 0.1524)
				)
			)
		)
		(duplicate_pad_numbers_are_jumpers no)
		(fp_line
			(start 0.508 -0.9398)
			(end -0.508 -0.9398)
			(stroke
				(width 0.1524)
				(type default)
			)
			(layer "F.SilkS")
		)
		(fp_line
			(start -0.508 -0.9398)
			(end -0.508 0.9398)
			(stroke
				(width 0.1524)
				(type default)
			)
			(layer "F.SilkS")
		)
		(fp_rect
			(start -0.508 0.9398)
			(end 0.508 -0.9398)
			(stroke
				(width 0)
				(type default)
			)
			(fill no)
			(layer "F.CrtYd")
		)
		(fp_rect
			(start -0.508 0.9398)
			(end 0.508 -0.9398)
			(stroke
				(width 0)
				(type default)
			)
			(fill no)
			(layer "F.Fab")
		)
		(pad "1" smd custom
			(at 0 -0.4445 180)
			(size 0.1397 0.1397)
			(layers "F.Cu" "F.Mask" "F.Paste")
			(net "BMC_I2C2_MINI2_SCL_S")
			(options
				(clearance outline)
				(anchor circle)
			)
			(primitives
				(gr_poly
					(pts
						(arc
							(start -0.1778 -0.2794)
							(mid -0.249642 -0.249642)
							(end -0.2794 -0.1778)
						)
						(arc
							(start -0.2794 0.1778)
							(mid -0.249642 0.249642)
							(end -0.1778 0.2794)
						)
						(arc
							(start 0.1778 0.2794)
							(mid 0.249642 0.249642)
							(end 0.2794 0.1778)
						)
						(arc
							(start 0.2794 -0.1778)
							(mid 0.249642 -0.249642)
							(end 0.1778 -0.2794)
						)
					)
					(width 0)
					(fill yes)
				)
			)
		)
		(pad "2" smd custom
			(at 0 0.4445 180)
			(size 0.1397 0.1397)
			(layers "F.Cu" "F.Mask" "F.Paste")
			(net "BMC_I2C2_MINI2_SCL")
			(options
				(clearance outline)
				(anchor circle)
			)
			(primitives
				(gr_poly
					(pts
						(arc
							(start -0.1778 -0.2794)
							(mid -0.249642 -0.249642)
							(end -0.2794 -0.1778)
						)
						(arc
							(start -0.2794 0.1778)
							(mid -0.249642 0.249642)
							(end -0.1778 0.2794)
						)
						(arc
							(start 0.1778 0.2794)
							(mid 0.249642 0.249642)
							(end 0.2794 0.1778)
						)
						(arc
							(start 0.2794 -0.1778)
							(mid 0.249642 -0.249642)
							(end 0.1778 -0.2794)
						)
					)
					(width 0)
					(fill yes)
				)
			)
		)
	)
	(footprint ""
		(layer "F.Cu")
		(at 210.70824 -26.83002 90)
		(property "Reference" "R839"
			(at 0 0 90)
			(layer "F.SilkS")
			(hide yes)
			(effects
				(font
					(size 1.27 1.27)
				)
			)
		)
		(property "Value" "4K7R2F-GP"
			(at 0.064008 -3.993896 90)
			(unlocked yes)
			(layer "F.Fab")
			(hide yes)
			(effects
				(font
					(size 1.016 1.016)
					(thickness 0.1524)
				)
			)
		)
		(property "Device Type" "R402H16"
			(at 0.064008 -5.517896 90)
			(unlocked yes)
			(layer "F.Fab")
			(hide yes)
			(effects
				(font
					(size 1.016 1.016)
					(thickness 0.1524)
				)
			)
		)
		(duplicate_pad_numbers_are_jumpers no)
		(fp_line
			(start 0.508 -0.9398)
			(end -0.508 -0.9398)
			(stroke
				(width 0.1524)
				(type default)
			)
			(layer "F.SilkS")
		)
		(fp_line
			(start -0.508 -0.9398)
			(end -0.508 0.9398)
			(stroke
				(width 0.1524)
				(type default)
			)
			(layer "F.SilkS")
		)
		(fp_rect
			(start -0.508 0.9398)
			(end 0.508 -0.9398)
			(stroke
				(width 0)
				(type default)
			)
			(fill no)
			(layer "F.CrtYd")
		)
		(fp_rect
			(start -0.508 0.9398)
			(end 0.508 -0.9398)
			(stroke
				(width 0)
				(type default)
			)
			(fill no)
			(layer "F.Fab")
		)
		(pad "1" smd custom
			(at 0 -0.4445 90)
			(size 0.1397 0.1397)
			(layers "F.Cu" "F.Mask" "F.Paste")
			(net "DUT_VDDO")
			(options
				(clearance outline)
				(anchor circle)
			)
			(primitives
				(gr_poly
					(pts
						(arc
							(start -0.1778 -0.2794)
							(mid -0.249642 -0.249642)
							(end -0.2794 -0.1778)
						)
						(arc
							(start -0.2794 0.1778)
							(mid -0.249642 0.249642)
							(end -0.1778 0.2794)
						)
						(arc
							(start 0.1778 0.2794)
							(mid 0.249642 0.249642)
							(end 0.2794 0.1778)
						)
						(arc
							(start 0.2794 -0.1778)
							(mid 0.249642 -0.249642)
							(end 0.1778 -0.2794)
						)
					)
					(width 0)
					(fill yes)
				)
			)
		)
		(pad "2" smd custom
			(at 0 0.4445 90)
			(size 0.1397 0.1397)
			(layers "F.Cu" "F.Mask" "F.Paste")
			(net "DUT_TAP_SEL")
			(options
				(clearance outline)
				(anchor circle)
			)
			(primitives
				(gr_poly
					(pts
						(arc
							(start -0.1778 -0.2794)
							(mid -0.249642 -0.249642)
							(end -0.2794 -0.1778)
						)
						(arc
							(start -0.2794 0.1778)
							(mid -0.249642 0.249642)
							(end -0.1778 0.2794)
						)
						(arc
							(start 0.1778 0.2794)
							(mid 0.249642 0.249642)
							(end 0.2794 0.1778)
						)
						(arc
							(start 0.2794 -0.1778)
							(mid 0.249642 -0.249642)
							(end 0.1778 -0.2794)
						)
					)
					(width 0)
					(fill yes)
				)
			)
		)
	)
	(footprint ""
		(layer "F.Cu")
		(at 204.3684 -26.1112 -90)
		(property "Reference" "C136"
			(at 0 0 270)
			(layer "F.SilkS")
			(hide yes)
			(effects
				(font
					(size 1.27 1.27)
				)
			)
		)
		(property "Value" "SCD1U10V2KX-5GP"
			(at 1.1811 -2.7051 270)
			(unlocked yes)
			(layer "F.Fab")
			(hide yes)
			(effects
				(font
					(size 1.016 1.016)
					(thickness 0.1524)
				)
			)
		)
		(property "Device Type" "C402H22"
			(at 1.1811 -4.2291 270)
			(unlocked yes)
			(layer "F.Fab")
			(hide yes)
			(effects
				(font
					(size 1.016 1.016)
					(thickness 0.1524)
				)
			)
		)
		(duplicate_pad_numbers_are_jumpers no)
		(fp_rect
			(start -0.4318 0.9525)
			(end 0.4318 -0.9525)
			(stroke
				(width 0)
				(type default)
			)
			(fill no)
			(layer "F.CrtYd")
		)
		(fp_rect
			(start -0.4318 0.9525)
			(end 0.4318 -0.9525)
			(stroke
				(width 0)
				(type default)
			)
			(fill no)
			(layer "F.Fab")
		)
		(pad "1" smd custom
			(at 0 -0.4445 270)
			(size 0.1524 0.1524)
			(layers "F.Cu" "F.Mask" "F.Paste")
			(net "P3V3_STBY")
			(options
				(clearance outline)
				(anchor circle)
			)
			(primitives
				(gr_poly
					(pts
						(arc
							(start 0.3048 -0.2032)
							(mid 0.275042 -0.275042)
							(end 0.2032 -0.3048)
						)
						(arc
							(start -0.2032 -0.3048)
							(mid -0.275042 -0.275042)
							(end -0.3048 -0.2032)
						)
						(arc
							(start -0.3048 0.2032)
							(mid -0.275042 0.275042)
							(end -0.2032 0.3048)
						)
						(arc
							(start 0.2032 0.3048)
							(mid 0.275042 0.275042)
							(end 0.3048 0.2032)
						)
					)
					(width 0)
					(fill yes)
				)
			)
		)
		(pad "2" smd custom
			(at 0 0.4445 270)
			(size 0.1524 0.1524)
			(layers "F.Cu" "F.Mask" "F.Paste")
			(net "GND")
			(options
				(clearance outline)
				(anchor circle)
			)
			(primitives
				(gr_poly
					(pts
						(arc
							(start 0.3048 -0.2032)
							(mid 0.275042 -0.275042)
							(end 0.2032 -0.3048)
						)
						(arc
							(start -0.2032 -0.3048)
							(mid -0.275042 -0.275042)
							(end -0.3048 -0.2032)
						)
						(arc
							(start -0.3048 0.2032)
							(mid -0.275042 0.275042)
							(end -0.2032 0.3048)
						)
						(arc
							(start 0.2032 0.3048)
							(mid 0.275042 0.275042)
							(end 0.3048 0.2032)
						)
					)
					(width 0)
					(fill yes)
				)
			)
		)
	)
	(footprint ""
		(layer "F.Cu")
		(at 33.4772 -77.8256 90)
		(property "Reference" "PR63"
			(at 0 0 90)
			(layer "F.SilkS")
			(hide yes)
			(effects
				(font
					(size 1.27 1.27)
				)
			)
		)
		(property "Value" "0R3J-0-U-GP"
			(at -0.0254 -2.5146 90)
			(unlocked yes)
			(layer "F.Fab")
			(hide yes)
			(effects
				(font
					(size 1.016 1.016)
					(thickness 0.1524)
				)
			)
		)
		(property "Device Type" "R603H22"
			(at -0.0254 -4.0386 90)
			(unlocked yes)
			(layer "F.Fab")
			(hide yes)
			(effects
				(font
					(size 1.016 1.016)
					(thickness 0.1524)
				)
			)
		)
		(duplicate_pad_numbers_are_jumpers no)
		(fp_line
			(start 0.2032 0)
			(end 0.4826 0)
			(stroke
				(width 0.2032)
				(type default)
			)
			(layer "F.SilkS")
		)
		(fp_line
			(start -0.4826 0)
			(end -0.2032 0)
			(stroke
				(width 0.2032)
				(type default)
			)
			(layer "F.SilkS")
		)
		(fp_rect
			(start -0.5842 1.3335)
			(end 0.5842 -1.3335)
			(stroke
				(width 0)
				(type default)
			)
			(fill no)
			(layer "F.CrtYd")
		)
		(fp_rect
			(start -0.5842 1.3335)
			(end 0.5842 -1.3335)
			(stroke
				(width 0)
				(type default)
			)
			(fill no)
			(layer "F.Fab")
		)
		(pad "1" smd custom
			(at 0 -0.762 90)
			(size 0.2159 0.2159)
			(layers "F.Cu" "F.Mask" "F.Paste")
			(net "P5V_STBY_BS")
			(options
				(clearance outline)
				(anchor circle)
			)
			(primitives
				(gr_poly
					(pts
						(arc
							(start -0.3302 -0.4318)
							(mid -0.402042 -0.402042)
							(end -0.4318 -0.3302)
						)
						(arc
							(start -0.4318 0.3302)
							(mid -0.402042 0.402042)
							(end -0.3302 0.4318)
						)
						(arc
							(start 0.3302 0.4318)
							(mid 0.402042 0.402042)
							(end 0.4318 0.3302)
						)
						(arc
							(start 0.4318 -0.3302)
							(mid 0.402042 -0.402042)
							(end 0.3302 -0.4318)
						)
					)
					(width 0)
					(fill yes)
				)
			)
		)
		(pad "2" smd custom
			(at 0 0.762 90)
			(size 0.2159 0.2159)
			(layers "F.Cu" "F.Mask" "F.Paste")
			(net "P5V_STBY_BS_RC")
			(options
				(clearance outline)
				(anchor circle)
			)
			(primitives
				(gr_poly
					(pts
						(arc
							(start -0.3302 -0.4318)
							(mid -0.402042 -0.402042)
							(end -0.4318 -0.3302)
						)
						(arc
							(start -0.4318 0.3302)
							(mid -0.402042 0.402042)
							(end -0.3302 0.4318)
						)
						(arc
							(start 0.3302 0.4318)
							(mid 0.402042 0.402042)
							(end 0.4318 0.3302)
						)
						(arc
							(start 0.4318 -0.3302)
							(mid 0.402042 -0.402042)
							(end 0.3302 -0.4318)
						)
					)
					(width 0)
					(fill yes)
				)
			)
		)
	)
	(footprint ""
		(layer "F.Cu")
		(at 271.442942 -5.75183 180)
		(property "Reference" "R253"
			(at 0 0 180)
			(layer "F.SilkS")
			(hide yes)
			(effects
				(font
					(size 1.27 1.27)
				)
			)
		)
		(property "Value" "4K7R2F-GP"
			(at 0.064008 -3.993896 180)
			(unlocked yes)
			(layer "F.Fab")
			(hide yes)
			(effects
				(font
					(size 1.016 1.016)
					(thickness 0.1524)
				)
			)
		)
		(property "Device Type" "R402H16"
			(at 0.064008 -5.517896 180)
			(unlocked yes)
			(layer "F.Fab")
			(hide yes)
			(effects
				(font
					(size 1.016 1.016)
					(thickness 0.1524)
				)
			)
		)
		(duplicate_pad_numbers_are_jumpers no)
		(fp_line
			(start 0.508 -0.9398)
			(end -0.508 -0.9398)
			(stroke
				(width 0.1524)
				(type default)
			)
			(layer "F.SilkS")
		)
		(fp_line
			(start -0.508 -0.9398)
			(end -0.508 0.9398)
			(stroke
				(width 0.1524)
				(type default)
			)
			(layer "F.SilkS")
		)
		(fp_rect
			(start -0.508 0.9398)
			(end 0.508 -0.9398)
			(stroke
				(width 0)
				(type default)
			)
			(fill no)
			(layer "F.CrtYd")
		)
		(fp_rect
			(start -0.508 0.9398)
			(end 0.508 -0.9398)
			(stroke
				(width 0)
				(type default)
			)
			(fill no)
			(layer "F.Fab")
		)
		(pad "1" smd custom
			(at 0 -0.4445 180)
			(size 0.1397 0.1397)
			(layers "F.Cu" "F.Mask" "F.Paste")
			(net "P3V3_STBY")
			(options
				(clearance outline)
				(anchor circle)
			)
			(primitives
				(gr_poly
					(pts
						(arc
							(start -0.1778 -0.2794)
							(mid -0.249642 -0.249642)
							(end -0.2794 -0.1778)
						)
						(arc
							(start -0.2794 0.1778)
							(mid -0.249642 0.249642)
							(end -0.1778 0.2794)
						)
						(arc
							(start 0.1778 0.2794)
							(mid 0.249642 0.249642)
							(end 0.2794 0.1778)
						)
						(arc
							(start 0.2794 -0.1778)
							(mid 0.249642 -0.249642)
							(end 0.1778 -0.2794)
						)
					)
					(width 0)
					(fill yes)
				)
			)
		)
		(pad "2" smd custom
			(at 0 0.4445 180)
			(size 0.1397 0.1397)
			(layers "F.Cu" "F.Mask" "F.Paste")
			(net "CLK_P_7_R")
			(options
				(clearance outline)
				(anchor circle)
			)
			(primitives
				(gr_poly
					(pts
						(arc
							(start -0.1778 -0.2794)
							(mid -0.249642 -0.249642)
							(end -0.2794 -0.1778)
						)
						(arc
							(start -0.2794 0.1778)
							(mid -0.249642 0.249642)
							(end -0.1778 0.2794)
						)
						(arc
							(start 0.1778 0.2794)
							(mid 0.249642 0.249642)
							(end 0.2794 0.1778)
						)
						(arc
							(start 0.2794 -0.1778)
							(mid 0.249642 -0.249642)
							(end 0.1778 -0.2794)
						)
					)
					(width 0)
					(fill yes)
				)
			)
		)
	)
	(footprint ""
		(layer "F.Cu")
		(at 327.914 -76.2 -90)
		(property "Reference" "R14"
			(at 0 0 270)
			(layer "F.SilkS")
			(hide yes)
			(effects
				(font
					(size 1.27 1.27)
				)
			)
		)
		(property "Value" "0R2J-2-GP"
			(at 0.064008 -3.993896 270)
			(unlocked yes)
			(layer "F.Fab")
			(hide yes)
			(effects
				(font
					(size 1.016 1.016)
					(thickness 0.1524)
				)
			)
		)
		(property "Device Type" "R402H16"
			(at 0.064008 -5.517896 270)
			(unlocked yes)
			(layer "F.Fab")
			(hide yes)
			(effects
				(font
					(size 1.016 1.016)
					(thickness 0.1524)
				)
			)
		)
		(duplicate_pad_numbers_are_jumpers no)
		(fp_line
			(start -0.508 -0.9398)
			(end -0.508 0.9398)
			(stroke
				(width 0.1524)
				(type default)
			)
			(layer "F.SilkS")
		)
		(fp_line
			(start 0.508 -0.9398)
			(end -0.508 -0.9398)
			(stroke
				(width 0.1524)
				(type default)
			)
			(layer "F.SilkS")
		)
		(fp_rect
			(start -0.508 0.9398)
			(end 0.508 -0.9398)
			(stroke
				(width 0)
				(type default)
			)
			(fill no)
			(layer "F.CrtYd")
		)
		(fp_rect
			(start -0.508 0.9398)
			(end 0.508 -0.9398)
			(stroke
				(width 0)
				(type default)
			)
			(fill no)
			(layer "F.Fab")
		)
		(pad "1" smd custom
			(at 0 -0.4445 270)
			(size 0.1397 0.1397)
			(layers "F.Cu" "F.Mask" "F.Paste")
			(net "AVS_ENB2_R")
			(options
				(clearance outline)
				(anchor circle)
			)
			(primitives
				(gr_poly
					(pts
						(arc
							(start -0.1778 -0.2794)
							(mid -0.249642 -0.249642)
							(end -0.2794 -0.1778)
						)
						(arc
							(start -0.2794 0.1778)
							(mid -0.249642 0.249642)
							(end -0.1778 0.2794)
						)
						(arc
							(start 0.1778 0.2794)
							(mid 0.249642 0.249642)
							(end 0.2794 0.1778)
						)
						(arc
							(start 0.2794 -0.1778)
							(mid 0.249642 -0.249642)
							(end 0.1778 -0.2794)
						)
					)
					(width 0)
					(fill yes)
				)
			)
		)
		(pad "2" smd custom
			(at 0 0.4445 270)
			(size 0.1397 0.1397)
			(layers "F.Cu" "F.Mask" "F.Paste")
			(net "AVS_ENB")
			(options
				(clearance outline)
				(anchor circle)
			)
			(primitives
				(gr_poly
					(pts
						(arc
							(start -0.1778 -0.2794)
							(mid -0.249642 -0.249642)
							(end -0.2794 -0.1778)
						)
						(arc
							(start -0.2794 0.1778)
							(mid -0.249642 0.249642)
							(end -0.1778 0.2794)
						)
						(arc
							(start 0.1778 0.2794)
							(mid 0.249642 0.249642)
							(end 0.2794 0.1778)
						)
						(arc
							(start 0.2794 -0.1778)
							(mid 0.249642 -0.249642)
							(end 0.1778 -0.2794)
						)
					)
					(width 0)
					(fill yes)
				)
			)
		)
	)
	(footprint ""
		(layer "F.Cu")
		(at 34.05886 -118.30812)
		(property "Reference" "TP227"
			(at 0 0 0)
			(layer "F.SilkS")
			(hide yes)
			(effects
				(font
					(size 1.27 1.27)
				)
			)
		)
		(property "Value" "TPAD28-2-GP"
			(at -0.0127 -1.6637 0)
			(unlocked yes)
			(layer "F.Fab")
			(hide yes)
			(effects
				(font
					(size 1.016 1.016)
					(thickness 0.1524)
				)
			)
		)
		(property "Device Type" "TPAD28"
			(at -0.0127 -3.1877 0)
			(unlocked yes)
			(layer "F.Fab")
			(hide yes)
			(effects
				(font
					(size 1.016 1.016)
					(thickness 0.1524)
				)
			)
		)
		(duplicate_pad_numbers_are_jumpers no)
		(fp_poly
			(pts
				(arc
					(start 0.3556 0)
					(mid -0.3556 0)
					(end 0.3556 0)
				)
			)
			(stroke
				(width 0)
				(type default)
			)
			(fill no)
			(layer "F.CrtYd")
		)
		(fp_poly
			(pts
				(arc
					(start 0.6096 0)
					(mid -0.6096 0)
					(end 0.6096 0)
				)
			)
			(stroke
				(width 0)
				(type default)
			)
			(fill no)
			(layer "F.Fab")
		)
		(pad "1" smd circle
			(at 0 0)
			(size 0.7112 0.7112)
			(layers "F.Cu" "F.Mask" "F.Paste")
			(net "TP_GPIOE2")
		)
	)
	(footprint ""
		(layer "F.Cu")
		(at 163.195 -33.528)
		(property "Reference" "C396"
			(at 0 0 0)
			(layer "F.SilkS")
			(hide yes)
			(effects
				(font
					(size 1.27 1.27)
				)
			)
		)
		(property "Value" "SCD22U10V2KX-1GP"
			(at 1.1811 -2.7051 0)
			(unlocked yes)
			(layer "F.Fab")
			(hide yes)
			(effects
				(font
					(size 1.016 1.016)
					(thickness 0.1524)
				)
			)
		)
		(property "Device Type" "C402H22"
			(at 1.1811 -4.2291 0)
			(unlocked yes)
			(layer "F.Fab")
			(hide yes)
			(effects
				(font
					(size 1.016 1.016)
					(thickness 0.1524)
				)
			)
		)
		(duplicate_pad_numbers_are_jumpers no)
		(fp_rect
			(start -0.4318 0.9525)
			(end 0.4318 -0.9525)
			(stroke
				(width 0)
				(type default)
			)
			(fill no)
			(layer "F.CrtYd")
		)
		(fp_rect
			(start -0.4318 0.9525)
			(end 0.4318 -0.9525)
			(stroke
				(width 0)
				(type default)
			)
			(fill no)
			(layer "F.Fab")
		)
		(pad "1" smd custom
			(at 0 -0.4445)
			(size 0.1524 0.1524)
			(layers "F.Cu" "F.Mask" "F.Paste")
			(net "PCIE_TX_CAP_P88")
			(options
				(clearance outline)
				(anchor circle)
			)
			(primitives
				(gr_poly
					(pts
						(arc
							(start 0.3048 -0.2032)
							(mid 0.275042 -0.275042)
							(end 0.2032 -0.3048)
						)
						(arc
							(start -0.2032 -0.3048)
							(mid -0.275042 -0.275042)
							(end -0.3048 -0.2032)
						)
						(arc
							(start -0.3048 0.2032)
							(mid -0.275042 0.275042)
							(end -0.2032 0.3048)
						)
						(arc
							(start 0.2032 0.3048)
							(mid 0.275042 0.275042)
							(end 0.3048 0.2032)
						)
					)
					(width 0)
					(fill yes)
				)
			)
		)
		(pad "2" smd custom
			(at 0 0.4445)
			(size 0.1524 0.1524)
			(layers "F.Cu" "F.Mask" "F.Paste")
			(net "PCIE_TX_P88")
			(options
				(clearance outline)
				(anchor circle)
			)
			(primitives
				(gr_poly
					(pts
						(arc
							(start 0.3048 -0.2032)
							(mid 0.275042 -0.275042)
							(end 0.2032 -0.3048)
						)
						(arc
							(start -0.2032 -0.3048)
							(mid -0.275042 -0.275042)
							(end -0.3048 -0.2032)
						)
						(arc
							(start -0.3048 0.2032)
							(mid -0.275042 0.275042)
							(end -0.2032 0.3048)
						)
						(arc
							(start 0.2032 0.3048)
							(mid 0.275042 0.275042)
							(end 0.3048 0.2032)
						)
					)
					(width 0)
					(fill yes)
				)
			)
		)
	)
)
